# SCM (Grand Teton) — schematic netlist excerpt (pin names and nets, part order shuffled) for the footprints in the layout excerpt that follows; sources: Cadence DE-HDL packaged netlist, KiCad conversion of 12092022_DA0F0TMDCD0_F0T_Management_Board_D_brd_V3_OCP.brd

C3  Q_CAP  1UF 25V 10% X6S  pkg C0402  page 20 : A = P1V2_AUX ; B = GND
R425  Q_RES  33.2 1% CHIP  pkg 0402LF  page 12 : A = SMB_BMC_MM14_R_SCL ; B = SMB_BMC_MM14_SCL

(kicad_pcb
	(version 20260206)
	(generator "pcbnew")
	(generator_version "10.0")
	(general
		(thickness 1.6)
		(legacy_teardrops no)
	)
	(paper "A4")
	(title_block
		(title "12092022_DA0F0TMDCD0_F0T_Management_Board_D_brd_V3_OCP.brd")
		(comment 1 "Grand Teton / footprints 903-904 of 1440")
	)
	(layers
		(0 "F.Cu" signal "TOP")
		(4 "In1.Cu" signal "GND")
		(6 "In2.Cu" signal "IN1")
		(8 "In3.Cu" signal "GND1")
		(10 "In4.Cu" signal "IN2")
		(12 "In5.Cu" signal "VCC")
		(14 "In6.Cu" signal "VCC1")
		(16 "In7.Cu" signal "IN3")
		(18 "In8.Cu" signal "GND2")
		(20 "In9.Cu" signal "IN4")
		(22 "In10.Cu" signal "GND3")
		(2 "B.Cu" signal "BOTTOM")
		(9 "F.Adhes" user "F.Adhesive")
		(11 "B.Adhes" user "B.Adhesive")
		(13 "F.Paste" user "Package Geometry/Pastemask Top")
		(15 "B.Paste" user "Package Geometry/Pastemask Bottom")
		(5 "F.SilkS" user "Ref Des/Silkscreen Top")
		(7 "B.SilkS" user "Ref Des/Silkscreen Bottom")
		(1 "F.Mask" user "Board Geometry/Soldermask Top")
		(3 "B.Mask" user "Board Geometry/Soldermask Bottom")
		(17 "Dwgs.User" user "User.Drawings")
		(19 "Cmts.User" user "User.Comments")
		(21 "Eco1.User" user "User.Eco1")
		(23 "Eco2.User" user "User.Eco2")
		(25 "Edge.Cuts" user "Board Geometry/Outline")
		(27 "Margin" user)
		(31 "F.CrtYd" user "Package Geometry/Place Bound Top")
		(29 "B.CrtYd" user "Package Geometry/Place Bound Bottom")
		(35 "F.Fab" user "Ref Des/Assembly Top")
		(33 "B.Fab" user "Ref Des/Assembly Bottom")
	)
	(footprint ""
		(layer "B.Cu")
		(at 71.034656 -54.23662)
		(property "Reference" "C3"
			(at 0 0 0)
			(layer "B.SilkS")
			(hide yes)
			(effects
				(font
					(size 1.27 1.27)
				)
				(justify mirror)
			)
		)
		(property "Value" ""
			(at 0 0 0)
			(layer "B.Fab")
			(effects
				(font
					(size 1.27 1.27)
				)
				(justify mirror)
			)
		)
		(duplicate_pad_numbers_are_jumpers no)
		(fp_line
			(start -0.7874 -0.4064)
			(end -0.7874 0.4064)
			(stroke
				(width 0.1524)
				(type default)
			)
			(layer "B.SilkS")
		)
		(fp_line
			(start -0.7874 0.4064)
			(end 0.7874 0.4064)
			(stroke
				(width 0.1524)
				(type default)
			)
			(layer "B.SilkS")
		)
		(fp_line
			(start 0.7874 -0.4064)
			(end -0.7874 -0.4064)
			(stroke
				(width 0.1524)
				(type default)
			)
			(layer "B.SilkS")
		)
		(fp_line
			(start 0.7874 0.4064)
			(end 0.7874 -0.4064)
			(stroke
				(width 0.1524)
				(type default)
			)
			(layer "B.SilkS")
		)
		(fp_line
			(start -0.67945 -0.3048)
			(end -0.67945 0.3048)
			(stroke
				(width 0.1)
				(type default)
			)
			(layer "B.Fab")
		)
		(fp_line
			(start -0.67945 0.3048)
			(end -0.120396 0.3048)
			(stroke
				(width 0.1)
				(type default)
			)
			(layer "B.Fab")
		)
		(fp_line
			(start -0.12065 -0.3048)
			(end -0.67945 -0.3048)
			(stroke
				(width 0.1)
				(type default)
			)
			(layer "B.Fab")
		)
		(fp_line
			(start -0.12065 -0.2794)
			(end -0.12065 -0.3048)
			(stroke
				(width 0.1)
				(type default)
			)
			(layer "B.Fab")
		)
		(fp_line
			(start -0.120396 0.2794)
			(end 0.12065 0.2794)
			(stroke
				(width 0.1)
				(type default)
			)
			(layer "B.Fab")
		)
		(fp_line
			(start -0.120396 0.3048)
			(end -0.120396 0.2794)
			(stroke
				(width 0.1)
				(type default)
			)
			(layer "B.Fab")
		)
		(fp_line
			(start 0.12065 -0.305054)
			(end 0.12065 -0.2794)
			(stroke
				(width 0.1)
				(type default)
			)
			(layer "B.Fab")
		)
		(fp_line
			(start 0.12065 -0.2794)
			(end -0.12065 -0.2794)
			(stroke
				(width 0.1)
				(type default)
			)
			(layer "B.Fab")
		)
		(fp_line
			(start 0.12065 0.2794)
			(end 0.12065 0.3048)
			(stroke
				(width 0.1)
				(type default)
			)
			(layer "B.Fab")
		)
		(fp_line
			(start 0.12065 0.3048)
			(end 0.67945 0.3048)
			(stroke
				(width 0.1)
				(type default)
			)
			(layer "B.Fab")
		)
		(fp_line
			(start 0.67945 -0.305054)
			(end 0.12065 -0.305054)
			(stroke
				(width 0.1)
				(type default)
			)
			(layer "B.Fab")
		)
		(fp_line
			(start 0.67945 0.3048)
			(end 0.67945 -0.305054)
			(stroke
				(width 0.1)
				(type default)
			)
			(layer "B.Fab")
		)
		(pad "1" smd circle
			(at 0.40005 0 180)
			(size 0 0)
			(layers "B.Cu" "B.Mask" "B.Paste")
			(net "P1V2_AUX")
		)
		(pad "2" smd circle
			(at -0.40005 0 180)
			(size 0 0)
			(layers "B.Cu" "B.Mask" "B.Paste")
			(net "GND")
		)
	)
	(footprint ""
		(layer "B.Cu")
		(at 39.930832 -48.915828)
		(property "Reference" "R425"
			(at 0 0 0)
			(layer "B.SilkS")
			(hide yes)
			(effects
				(font
					(size 1.27 1.27)
				)
				(justify mirror)
			)
		)
		(property "Value" ""
			(at 0 0 0)
			(layer "B.Fab")
			(effects
				(font
					(size 1.27 1.27)
				)
				(justify mirror)
			)
		)
		(duplicate_pad_numbers_are_jumpers no)
		(fp_line
			(start -0.7874 -0.4064)
			(end -0.7874 0.4064)
			(stroke
				(width 0.1524)
				(type default)
			)
			(layer "B.SilkS")
		)
		(fp_line
			(start -0.7874 0.4064)
			(end 0.7874 0.4064)
			(stroke
				(width 0.1524)
				(type default)
			)
			(layer "B.SilkS")
		)
		(fp_line
			(start 0.7874 -0.4064)
			(end -0.7874 -0.4064)
			(stroke
				(width 0.1524)
				(type default)
			)
			(layer "B.SilkS")
		)
		(fp_line
			(start 0.7874 0.4064)
			(end 0.7874 -0.4064)
			(stroke
				(width 0.1524)
				(type default)
			)
			(layer "B.SilkS")
		)
		(fp_line
			(start -0.67945 -0.3048)
			(end -0.67945 0.3048)
			(stroke
				(width 0.1)
				(type default)
			)
			(layer "B.Fab")
		)
		(fp_line
			(start -0.67945 0.3048)
			(end -0.120396 0.3048)
			(stroke
				(width 0.1)
				(type default)
			)
			(layer "B.Fab")
		)
		(fp_line
			(start -0.12065 -0.3048)
			(end -0.67945 -0.3048)
			(stroke
				(width 0.1)
				(type default)
			)
			(layer "B.Fab")
		)
		(fp_line
			(start -0.12065 -0.2794)
			(end -0.12065 -0.3048)
			(stroke
				(width 0.1)
				(type default)
			)
			(layer "B.Fab")
		)
		(fp_line
			(start -0.120396 0.2794)
			(end 0.12065 0.2794)
			(stroke
				(width 0.1)
				(type default)
			)
			(layer "B.Fab")
		)
		(fp_line
			(start -0.120396 0.3048)
			(end -0.120396 0.2794)
			(stroke
				(width 0.1)
				(type default)
			)
			(layer "B.Fab")
		)
		(fp_line
			(start 0.12065 -0.305054)
			(end 0.12065 -0.2794)
			(stroke
				(width 0.1)
				(type default)
			)
			(layer "B.Fab")
		)
		(fp_line
			(start 0.12065 -0.2794)
			(end -0.12065 -0.2794)
			(stroke
				(width 0.1)
				(type default)
			)
			(layer "B.Fab")
		)
		(fp_line
			(start 0.12065 0.2794)
			(end 0.12065 0.3048)
			(stroke
				(width 0.1)
				(type default)
			)
			(layer "B.Fab")
		)
		(fp_line
			(start 0.12065 0.3048)
			(end 0.67945 0.3048)
			(stroke
				(width 0.1)
				(type default)
			)
			(layer "B.Fab")
		)
		(fp_line
			(start 0.67945 -0.305054)
			(end 0.12065 -0.305054)
			(stroke
				(width 0.1)
				(type default)
			)
			(layer "B.Fab")
		)
		(fp_line
			(start 0.67945 0.3048)
			(end 0.67945 -0.305054)
			(stroke
				(width 0.1)
				(type default)
			)
			(layer "B.Fab")
		)
		(pad "1" smd circle
			(at 0.40005 0 180)
			(size 0 0)
			(layers "B.Cu" "B.Mask" "B.Paste")
			(net "SMB_BMC_MM14_R_SCL")
		)
		(pad "2" smd circle
			(at -0.40005 0 180)
			(size 0 0)
			(layers "B.Cu" "B.Mask" "B.Paste")
			(net "SMB_BMC_MM14_SCL")
		)
	)
)
